# T6G (Grand Teton) — schematic netlist excerpt (pin names and nets, part order shuffled) for the footprints in the layout excerpt that follows; sources: Cadence DE-HDL packaged netlist, KiCad conversion of 04192023_DAF0TMB3IC0_F0TG_MB_C_brd_V02_OCP.brd

C2610  Q_CAP  22UF 4V 20% X6S  pkg C0402  page 70 : A = PVDD11_S3_P0 ; B = GND
R4130  Q_RES  100K 1% CHIP  pkg 0402LF  page 125 : A = P3V3_AUX ; B = GPU_3V3IO_RSVD1_FFU_ISO

(kicad_pcb
	(version 20260206)
	(generator "pcbnew")
	(generator_version "10.0")
	(general
		(thickness 1.6)
		(legacy_teardrops no)
	)
	(paper "A4")
	(title_block
		(title "04192023_DAF0TMB3IC0_F0TG_MB_C_brd_V02_OCP.brd")
		(comment 1 "Grand Teton / footprints 5507-5508 of 8354")
	)
	(layers
		(0 "F.Cu" signal "TOP")
		(4 "In1.Cu" signal "GND")
		(6 "In2.Cu" signal "IN1")
		(8 "In3.Cu" signal "GND1")
		(10 "In4.Cu" signal "IN2")
		(12 "In5.Cu" signal "GND2")
		(14 "In6.Cu" signal "IN3")
		(16 "In7.Cu" signal "GND3")
		(18 "In8.Cu" signal "VCC")
		(20 "In9.Cu" signal "VCC1")
		(22 "In10.Cu" signal "GND4")
		(24 "In11.Cu" signal "IN4")
		(26 "In12.Cu" signal "GND5")
		(28 "In13.Cu" signal "IN5")
		(30 "In14.Cu" signal "GND6")
		(32 "In15.Cu" signal "IN6")
		(34 "In16.Cu" signal "GND7")
		(2 "B.Cu" signal "BOTTOM")
		(9 "F.Adhes" user "F.Adhesive")
		(11 "B.Adhes" user "B.Adhesive")
		(13 "F.Paste" user "Package Geometry/Pastemask Top")
		(15 "B.Paste" user "Package Geometry/Pastemask Bottom")
		(5 "F.SilkS" user "Ref Des/Silkscreen Top")
		(7 "B.SilkS" user "Ref Des/Silkscreen Bottom")
		(1 "F.Mask" user "Board Geometry/Soldermask Top")
		(3 "B.Mask" user "Board Geometry/Soldermask Bottom")
		(17 "Dwgs.User" user "User.Drawings")
		(19 "Cmts.User" user "User.Comments")
		(21 "Eco1.User" user "User.Eco1")
		(23 "Eco2.User" user "User.Eco2")
		(25 "Edge.Cuts" user "Board Geometry/Outline")
		(27 "Margin" user)
		(31 "F.CrtYd" user "Package Geometry/Place Bound Top")
		(29 "B.CrtYd" user "Package Geometry/Place Bound Bottom")
		(35 "F.Fab" user "Ref Des/Assembly Top")
		(33 "B.Fab" user "Ref Des/Assembly Bottom")
	)
	(footprint ""
		(layer "B.Cu")
		(at 359.417112 -261.747762 90)
		(property "Reference" "C2610"
			(at 0 0 90)
			(layer "B.SilkS")
			(hide yes)
			(effects
				(font
					(size 1.27 1.27)
				)
				(justify mirror)
			)
		)
		(property "Value" ""
			(at 0 0 90)
			(layer "B.Fab")
			(effects
				(font
					(size 1.27 1.27)
				)
				(justify mirror)
			)
		)
		(duplicate_pad_numbers_are_jumpers no)
		(fp_line
			(start 0.7874 -0.4064)
			(end -0.7874 -0.4064)
			(stroke
				(width 0.1524)
				(type default)
			)
			(layer "B.SilkS")
		)
		(fp_line
			(start -0.7874 -0.4064)
			(end -0.7874 0.4064)
			(stroke
				(width 0.1524)
				(type default)
			)
			(layer "B.SilkS")
		)
		(fp_line
			(start 0.7874 0.4064)
			(end 0.7874 -0.4064)
			(stroke
				(width 0.1524)
				(type default)
			)
			(layer "B.SilkS")
		)
		(fp_line
			(start -0.7874 0.4064)
			(end 0.7874 0.4064)
			(stroke
				(width 0.1524)
				(type default)
			)
			(layer "B.SilkS")
		)
		(fp_line
			(start 0.67945 -0.305054)
			(end 0.12065 -0.305054)
			(stroke
				(width 0.1)
				(type default)
			)
			(layer "B.Fab")
		)
		(fp_line
			(start 0.12065 -0.305054)
			(end 0.12065 -0.2794)
			(stroke
				(width 0.1)
				(type default)
			)
			(layer "B.Fab")
		)
		(fp_line
			(start -0.12065 -0.3048)
			(end -0.67945 -0.3048)
			(stroke
				(width 0.1)
				(type default)
			)
			(layer "B.Fab")
		)
		(fp_line
			(start -0.67945 -0.3048)
			(end -0.67945 0.3048)
			(stroke
				(width 0.1)
				(type default)
			)
			(layer "B.Fab")
		)
		(fp_line
			(start 0.12065 -0.2794)
			(end -0.12065 -0.2794)
			(stroke
				(width 0.1)
				(type default)
			)
			(layer "B.Fab")
		)
		(fp_line
			(start -0.12065 -0.2794)
			(end -0.12065 -0.3048)
			(stroke
				(width 0.1)
				(type default)
			)
			(layer "B.Fab")
		)
		(fp_line
			(start 0.12065 0.2794)
			(end 0.12065 0.3048)
			(stroke
				(width 0.1)
				(type default)
			)
			(layer "B.Fab")
		)
		(fp_line
			(start -0.120396 0.2794)
			(end 0.12065 0.2794)
			(stroke
				(width 0.1)
				(type default)
			)
			(layer "B.Fab")
		)
		(fp_line
			(start 0.67945 0.3048)
			(end 0.67945 -0.305054)
			(stroke
				(width 0.1)
				(type default)
			)
			(layer "B.Fab")
		)
		(fp_line
			(start 0.12065 0.3048)
			(end 0.67945 0.3048)
			(stroke
				(width 0.1)
				(type default)
			)
			(layer "B.Fab")
		)
		(fp_line
			(start -0.120396 0.3048)
			(end -0.120396 0.2794)
			(stroke
				(width 0.1)
				(type default)
			)
			(layer "B.Fab")
		)
		(fp_line
			(start -0.67945 0.3048)
			(end -0.120396 0.3048)
			(stroke
				(width 0.1)
				(type default)
			)
			(layer "B.Fab")
		)
		(pad "1" smd circle
			(at 0.40005 0 270)
			(size 0 0)
			(layers "B.Cu" "B.Mask" "B.Paste")
			(net "PVDD11_S3_P0")
		)
		(pad "2" smd circle
			(at -0.40005 0 270)
			(size 0 0)
			(layers "B.Cu" "B.Mask" "B.Paste")
			(net "GND")
		)
	)
	(footprint ""
		(layer "B.Cu")
		(at 163.387532 -432.37658 90)
		(property "Reference" "R4130"
			(at 0 0 90)
			(layer "B.SilkS")
			(hide yes)
			(effects
				(font
					(size 1.27 1.27)
				)
				(justify mirror)
			)
		)
		(property "Value" ""
			(at 0 0 90)
			(layer "B.Fab")
			(effects
				(font
					(size 1.27 1.27)
				)
				(justify mirror)
			)
		)
		(duplicate_pad_numbers_are_jumpers no)
		(fp_line
			(start 0.7874 -0.4064)
			(end -0.7874 -0.4064)
			(stroke
				(width 0.1524)
				(type default)
			)
			(layer "B.SilkS")
		)
		(fp_line
			(start -0.7874 -0.4064)
			(end -0.7874 0.4064)
			(stroke
				(width 0.1524)
				(type default)
			)
			(layer "B.SilkS")
		)
		(fp_line
			(start 0.7874 0.4064)
			(end 0.7874 -0.4064)
			(stroke
				(width 0.1524)
				(type default)
			)
			(layer "B.SilkS")
		)
		(fp_line
			(start -0.7874 0.4064)
			(end 0.7874 0.4064)
			(stroke
				(width 0.1524)
				(type default)
			)
			(layer "B.SilkS")
		)
		(fp_line
			(start 0.67945 -0.305054)
			(end 0.12065 -0.305054)
			(stroke
				(width 0.1)
				(type default)
			)
			(layer "B.Fab")
		)
		(fp_line
			(start 0.12065 -0.305054)
			(end 0.12065 -0.2794)
			(stroke
				(width 0.1)
				(type default)
			)
			(layer "B.Fab")
		)
		(fp_line
			(start -0.12065 -0.3048)
			(end -0.67945 -0.3048)
			(stroke
				(width 0.1)
				(type default)
			)
			(layer "B.Fab")
		)
		(fp_line
			(start -0.67945 -0.3048)
			(end -0.67945 0.3048)
			(stroke
				(width 0.1)
				(type default)
			)
			(layer "B.Fab")
		)
		(fp_line
			(start 0.12065 -0.2794)
			(end -0.12065 -0.2794)
			(stroke
				(width 0.1)
				(type default)
			)
			(layer "B.Fab")
		)
		(fp_line
			(start -0.12065 -0.2794)
			(end -0.12065 -0.3048)
			(stroke
				(width 0.1)
				(type default)
			)
			(layer "B.Fab")
		)
		(fp_line
			(start 0.12065 0.2794)
			(end 0.12065 0.3048)
			(stroke
				(width 0.1)
				(type default)
			)
			(layer "B.Fab")
		)
		(fp_line
			(start -0.120396 0.2794)
			(end 0.12065 0.2794)
			(stroke
				(width 0.1)
				(type default)
			)
			(layer "B.Fab")
		)
		(fp_line
			(start 0.67945 0.3048)
			(end 0.67945 -0.305054)
			(stroke
				(width 0.1)
				(type default)
			)
			(layer "B.Fab")
		)
		(fp_line
			(start 0.12065 0.3048)
			(end 0.67945 0.3048)
			(stroke
				(width 0.1)
				(type default)
			)
			(layer "B.Fab")
		)
		(fp_line
			(start -0.120396 0.3048)
			(end -0.120396 0.2794)
			(stroke
				(width 0.1)
				(type default)
			)
			(layer "B.Fab")
		)
		(fp_line
			(start -0.67945 0.3048)
			(end -0.120396 0.3048)
			(stroke
				(width 0.1)
				(type default)
			)
			(layer "B.Fab")
		)
		(pad "1" smd circle
			(at 0.40005 0 270)
			(size 0 0)
			(layers "B.Cu" "B.Mask" "B.Paste")
			(net "P3V3_AUX")
		)
		(pad "2" smd circle
			(at -0.40005 0 270)
			(size 0 0)
			(layers "B.Cu" "B.Mask" "B.Paste")
			(net "GPU_3V3IO_RSVD1_FFU_ISO")
		)
	)
)
